(kicad_pcb
	(version 20260206)
	(generator "pcbnew")
	(generator_version "10.0")
	(general
		(thickness 1.6)
		(legacy_teardrops no)
	)
	(paper "A4")
	(title_block
		(title "timecard-production-celestica-r4006 — R4006-B0001-02_R01.brd")
		(comment 1 "Time Appliance Project (Time Card) / footprints 291-295 of 1113")
	)
	(layers
		(0 "F.Cu" signal "TOP")
		(4 "In1.Cu" signal "L02_GND1")
		(6 "In2.Cu" signal "L03_SIG1")
		(8 "In3.Cu" signal "L04_GND2")
		(10 "In4.Cu" signal "L05_VCC1")
		(12 "In5.Cu" signal "L06_VCC2")
		(14 "In6.Cu" signal "L07_GND3")
		(16 "In7.Cu" signal "L08_SIG2")
		(18 "In8.Cu" signal "L09_GND4")
		(2 "B.Cu" signal "BOTTOM")
		(9 "F.Adhes" user "F.Adhesive")
		(11 "B.Adhes" user "B.Adhesive")
		(13 "F.Paste" user "Package Geometry/Pastemask Top")
		(15 "B.Paste" user "Package Geometry/Pastemask Bottom")
		(5 "F.SilkS" user "Ref Des/Silkscreen Top")
		(7 "B.SilkS" user "Ref Des/Silkscreen Bottom")
		(1 "F.Mask" user "Board Geometry/Soldermask Top")
		(3 "B.Mask" user "Board Geometry/Soldermask Bottom")
		(17 "Dwgs.User" user "User.Drawings")
		(19 "Cmts.User" user "User.Comments")
		(21 "Eco1.User" user "User.Eco1")
		(23 "Eco2.User" user "User.Eco2")
		(25 "Edge.Cuts" user "Board Geometry/Outline")
		(27 "Margin" user)
		(31 "F.CrtYd" user "Package Geometry/Place Bound Top")
		(29 "B.CrtYd" user "Package Geometry/Place Bound Bottom")
		(35 "F.Fab" user "Ref Des/Assembly Top")
		(33 "B.Fab" user "Ref Des/Assembly Bottom")
	)
	(footprint ""
		(layer "F.Cu")
		(at 162.56 -28.829 180)
		(property "Reference" "C305"
			(at -2.667 0.72263 0)
			(unlocked yes)
			(layer "F.SilkS")
			(effects
				(font
					(size 0.7874 0.5842)
					(thickness 0.1524)
				)
			)
		)
		(property "Value" "VAL*"
			(at 0.0762 2.067306 180)
			(unlocked yes)
			(layer "F.Fab")
			(hide yes)
			(effects
				(font
					(size 0.7874 0.5842)
					(thickness 0.1524)
				)
			)
		)
		(property "Tolerance" "TOL*"
			(at 0.0762 3.032506 180)
			(unlocked yes)
			(layer "Cmts.User")
			(hide yes)
			(effects
				(font
					(size 0.7874 0.5842)
					(thickness 0.1524)
				)
			)
		)
		(property "User Part Number" "PARTNUM*"
			(at 0.1016 4.023106 180)
			(unlocked yes)
			(layer "Cmts.User")
			(hide yes)
			(effects
				(font
					(size 0.7874 0.5842)
					(thickness 0.1524)
				)
			)
		)
		(property "Device Type" "CAPACITOR-G105-0B104-EK,0.1UF,A"
			(at 0.0508 1.127506 180)
			(unlocked yes)
			(layer "F.Fab")
			(hide yes)
			(effects
				(font
					(size 0.7874 0.5842)
					(thickness 0.1524)
				)
			)
		)
		(duplicate_pad_numbers_are_jumpers no)
		(fp_line
			(start 1.143 0.5588)
			(end 1.143 -0.5588)
			(stroke
				(width 0.1)
				(type default)
			)
			(layer "F.SilkS")
		)
		(fp_line
			(start 1.143 -0.5588)
			(end -1.143 -0.5588)
			(stroke
				(width 0.1)
				(type default)
			)
			(layer "F.SilkS")
		)
		(fp_line
			(start -1.143 0.5588)
			(end 1.143 0.5588)
			(stroke
				(width 0.1)
				(type default)
			)
			(layer "F.SilkS")
		)
		(fp_line
			(start -1.143 -0.5588)
			(end -1.143 0.5588)
			(stroke
				(width 0.1)
				(type default)
			)
			(layer "F.SilkS")
		)
		(fp_rect
			(start 1.143 -0.5588)
			(end -1.143 0.5588)
			(stroke
				(width 0)
				(type default)
			)
			(fill no)
			(layer "F.CrtYd")
		)
		(fp_line
			(start 0.508 0.3048)
			(end 0.508 -0.3048)
			(stroke
				(width 0.1)
				(type default)
			)
			(layer "F.Fab")
		)
		(fp_line
			(start 0.508 -0.3048)
			(end -0.508 -0.3048)
			(stroke
				(width 0.1)
				(type default)
			)
			(layer "F.Fab")
		)
		(fp_line
			(start -0.508 0.3048)
			(end 0.508 0.3048)
			(stroke
				(width 0.1)
				(type default)
			)
			(layer "F.Fab")
		)
		(fp_line
			(start -0.508 -0.3048)
			(end -0.508 0.3048)
			(stroke
				(width 0.1)
				(type default)
			)
			(layer "F.Fab")
		)
		(pad "1" smd rect
			(at -0.5334 0 180)
			(size 0.7112 0.6096)
			(layers "F.Cu" "F.Mask" "F.Paste")
			(net "SG")
		)
		(pad "2" smd rect
			(at 0.5334 0 180)
			(size 0.7112 0.6096)
			(layers "F.Cu" "F.Mask" "F.Paste")
			(net "XP3R3V_FPGA")
		)
		(zone
			(layer "F.Cu")
			(hatch none 0.5)
			(connect_pads
				(clearance 0)
			)
			(min_thickness 0.25)
			(keepout
				(tracks allowed)
				(vias not_allowed)
				(pads allowed)
				(copperpour not_allowed)
				(footprints allowed)
			)
			(placement
				(enabled no)
				(sheetname "")
			)
			(fill
				(thermal_gap 0.5)
				(thermal_bridge_width 0.5)
				(island_removal_mode 0)
			)
			(polygon
				(pts
					(xy 162.4838 -28.5242) (xy 162.6362 -28.5242) (xy 162.6362 -29.1338) (xy 162.4838 -29.1338)
				)
			)
		)
		(zone
			(layer "F.Cu")
			(hatch none 0.5)
			(connect_pads
				(clearance 0)
			)
			(min_thickness 0.25)
			(keepout
				(tracks not_allowed)
				(vias allowed)
				(pads allowed)
				(copperpour not_allowed)
				(footprints allowed)
			)
			(placement
				(enabled no)
				(sheetname "")
			)
			(fill
				(thermal_gap 0.5)
				(thermal_bridge_width 0.5)
				(island_removal_mode 0)
			)
			(polygon
				(pts
					(xy 162.4838 -28.5242) (xy 162.6362 -28.5242) (xy 162.6362 -29.1338) (xy 162.4838 -29.1338)
				)
			)
		)
	)
	(footprint ""
		(layer "F.Cu")
		(at 118.491 -28.0416 90)
		(property "Reference" "TP202"
			(at -2.8194 1.30175 90)
			(unlocked yes)
			(layer "F.SilkS")
			(effects
				(font
					(size 0.635 0.4064)
					(thickness 0.1524)
				)
				(justify left)
			)
		)
		(property "Value" ""
			(at 0 0 90)
			(layer "F.Fab")
			(effects
				(font
					(size 1.27 1.27)
				)
			)
		)
		(property "Device Type" "TP_PIONT-TP010CT020B030_PTH-TPA"
			(at -1.341882 0.996696 90)
			(unlocked yes)
			(layer "F.Fab")
			(hide yes)
			(effects
				(font
					(size 0.7874 0.5842)
					(thickness 0.1524)
				)
				(justify left)
			)
		)
		(duplicate_pad_numbers_are_jumpers no)
		(fp_poly
			(pts
				(arc
					(start 0 0.889)
					(mid 0 -0.889)
					(end 0 0.889)
				)
			)
			(stroke
				(width 0)
				(type default)
			)
			(fill no)
			(layer "B.CrtYd")
		)
		(fp_poly
			(pts
				(arc
					(start 0 0.889)
					(mid 0 -0.889)
					(end 0 0.889)
				)
			)
			(stroke
				(width 0)
				(type default)
			)
			(fill no)
			(layer "F.CrtYd")
		)
		(pad "1" thru_hole circle
			(at 0 0 90)
			(size 0.508 0.508)
			(drill 0.254)
			(layers "*.Cu" "*.Mask")
			(remove_unused_layers no)
			(net "IO_L22N_35")
			(clearance 0.1016)
			(padstack
				(mode front_inner_back)
				(layer "Inner"
					(shape circle)
					(size 0.508 0.508)
					(clearance 0.1016)
				)
				(layer "B.Cu"
					(shape circle)
					(size 0.762 0.762)
					(clearance -0.0254)
				)
			)
		)
	)
	(footprint ""
		(layer "F.Cu")
		(at 83.5152 -106.7308 180)
		(property "Reference" "C50"
			(at -0.3048 1.68783 0)
			(unlocked yes)
			(layer "F.SilkS")
			(effects
				(font
					(size 0.7874 0.5842)
					(thickness 0.1524)
				)
			)
		)
		(property "Value" "VAL*"
			(at 0.0762 3.134106 180)
			(unlocked yes)
			(layer "F.Fab")
			(hide yes)
			(effects
				(font
					(size 0.7874 0.5842)
					(thickness 0.1524)
				)
			)
		)
		(property "Tolerance" "TOL*"
			(at 0.0762 4.048506 180)
			(unlocked yes)
			(layer "Cmts.User")
			(hide yes)
			(effects
				(font
					(size 0.7874 0.5842)
					(thickness 0.1524)
				)
			)
		)
		(property "User Part Number" "PARTNUM*"
			(at 0.1016 5.013706 180)
			(unlocked yes)
			(layer "Cmts.User")
			(hide yes)
			(effects
				(font
					(size 0.7874 0.5842)
					(thickness 0.1524)
				)
			)
		)
		(property "Device Type" "CAPACITOR-G107-0F106-EM,10UF,2A"
			(at 0.0508 2.194306 180)
			(unlocked yes)
			(layer "F.Fab")
			(hide yes)
			(effects
				(font
					(size 0.7874 0.5842)
					(thickness 0.1524)
				)
			)
		)
		(duplicate_pad_numbers_are_jumpers no)
		(fp_line
			(start 1.5748 0.9398)
			(end 1.5748 -0.9398)
			(stroke
				(width 0.1)
				(type default)
			)
			(layer "F.SilkS")
		)
		(fp_line
			(start 1.5748 -0.9398)
			(end -1.5748 -0.9398)
			(stroke
				(width 0.1)
				(type default)
			)
			(layer "F.SilkS")
		)
		(fp_line
			(start -1.5748 0.9398)
			(end 1.5748 0.9398)
			(stroke
				(width 0.1)
				(type default)
			)
			(layer "F.SilkS")
		)
		(fp_line
			(start -1.5748 -0.9398)
			(end -1.5748 0.9398)
			(stroke
				(width 0.1)
				(type default)
			)
			(layer "F.SilkS")
		)
		(fp_rect
			(start 1.5748 -0.9398)
			(end -1.5748 0.9398)
			(stroke
				(width 0)
				(type default)
			)
			(fill no)
			(layer "F.CrtYd")
		)
		(fp_line
			(start 1.016 0.635)
			(end 1.016 -0.635)
			(stroke
				(width 0.1)
				(type default)
			)
			(layer "F.Fab")
		)
		(fp_line
			(start 1.016 -0.635)
			(end -1.016 -0.635)
			(stroke
				(width 0.1)
				(type default)
			)
			(layer "F.Fab")
		)
		(fp_line
			(start -1.016 0.635)
			(end 1.016 0.635)
			(stroke
				(width 0.1)
				(type default)
			)
			(layer "F.Fab")
		)
		(fp_line
			(start -1.016 -0.635)
			(end -1.016 0.635)
			(stroke
				(width 0.1)
				(type default)
			)
			(layer "F.Fab")
		)
		(pad "1" smd rect
			(at -0.8382 0 180)
			(size 0.9652 1.3716)
			(layers "F.Cu" "F.Mask" "F.Paste")
			(net "VIN_XP3R3")
		)
		(pad "2" smd rect
			(at 0.8382 0 180)
			(size 0.9652 1.3716)
			(layers "F.Cu" "F.Mask" "F.Paste")
			(net "SG")
		)
		(zone
			(layer "F.Cu")
			(hatch none 0.5)
			(connect_pads
				(clearance 0)
			)
			(min_thickness 0.25)
			(keepout
				(tracks allowed)
				(vias not_allowed)
				(pads allowed)
				(copperpour not_allowed)
				(footprints allowed)
			)
			(placement
				(enabled no)
				(sheetname "")
			)
			(fill
				(thermal_gap 0.5)
				(thermal_bridge_width 0.5)
				(island_removal_mode 0)
			)
			(polygon
				(pts
					(xy 83.2866 -106.0958) (xy 83.7438 -106.0958) (xy 83.7438 -107.3658) (xy 83.2866 -107.3658)
				)
			)
		)
	)
	(footprint ""
		(layer "F.Cu")
		(at 84.5312 -98.7298 180)
		(property "Reference" "C52"
			(at 4.6482 -6.18617 0)
			(unlocked yes)
			(layer "F.SilkS")
			(effects
				(font
					(size 0.7874 0.5842)
					(thickness 0.1524)
				)
			)
		)
		(property "Value" "VAL*"
			(at 0.0762 2.067306 180)
			(unlocked yes)
			(layer "F.Fab")
			(hide yes)
			(effects
				(font
					(size 0.7874 0.5842)
					(thickness 0.1524)
				)
			)
		)
		(property "Tolerance" "TOL*"
			(at 0.0762 3.032506 180)
			(unlocked yes)
			(layer "Cmts.User")
			(hide yes)
			(effects
				(font
					(size 0.7874 0.5842)
					(thickness 0.1524)
				)
			)
		)
		(property "User Part Number" "PARTNUM*"
			(at 0.1016 4.023106 180)
			(unlocked yes)
			(layer "Cmts.User")
			(hide yes)
			(effects
				(font
					(size 0.7874 0.5842)
					(thickness 0.1524)
				)
			)
		)
		(property "Device Type" "CAPACITOR-G105-0B104-EK,0.1UF,A"
			(at 0.0508 1.127506 180)
			(unlocked yes)
			(layer "F.Fab")
			(hide yes)
			(effects
				(font
					(size 0.7874 0.5842)
					(thickness 0.1524)
				)
			)
		)
		(duplicate_pad_numbers_are_jumpers no)
		(fp_line
			(start 1.143 0.5588)
			(end 1.143 -0.5588)
			(stroke
				(width 0.1)
				(type default)
			)
			(layer "F.SilkS")
		)
		(fp_line
			(start 1.143 -0.5588)
			(end -1.143 -0.5588)
			(stroke
				(width 0.1)
				(type default)
			)
			(layer "F.SilkS")
		)
		(fp_line
			(start -1.143 0.5588)
			(end 1.143 0.5588)
			(stroke
				(width 0.1)
				(type default)
			)
			(layer "F.SilkS")
		)
		(fp_line
			(start -1.143 -0.5588)
			(end -1.143 0.5588)
			(stroke
				(width 0.1)
				(type default)
			)
			(layer "F.SilkS")
		)
		(fp_rect
			(start 1.143 -0.5588)
			(end -1.143 0.5588)
			(stroke
				(width 0)
				(type default)
			)
			(fill no)
			(layer "F.CrtYd")
		)
		(fp_line
			(start 0.508 0.3048)
			(end 0.508 -0.3048)
			(stroke
				(width 0.1)
				(type default)
			)
			(layer "F.Fab")
		)
		(fp_line
			(start 0.508 -0.3048)
			(end -0.508 -0.3048)
			(stroke
				(width 0.1)
				(type default)
			)
			(layer "F.Fab")
		)
		(fp_line
			(start -0.508 0.3048)
			(end 0.508 0.3048)
			(stroke
				(width 0.1)
				(type default)
			)
			(layer "F.Fab")
		)
		(fp_line
			(start -0.508 -0.3048)
			(end -0.508 0.3048)
			(stroke
				(width 0.1)
				(type default)
			)
			(layer "F.Fab")
		)
		(pad "1" smd rect
			(at -0.5334 0 180)
			(size 0.7112 0.6096)
			(layers "F.Cu" "F.Mask" "F.Paste")
			(net "VIN_XP3R3")
		)
		(pad "2" smd rect
			(at 0.5334 0 180)
			(size 0.7112 0.6096)
			(layers "F.Cu" "F.Mask" "F.Paste")
			(net "SG")
		)
		(zone
			(layer "F.Cu")
			(hatch none 0.5)
			(connect_pads
				(clearance 0)
			)
			(min_thickness 0.25)
			(keepout
				(tracks allowed)
				(vias not_allowed)
				(pads allowed)
				(copperpour not_allowed)
				(footprints allowed)
			)
			(placement
				(enabled no)
				(sheetname "")
			)
			(fill
				(thermal_gap 0.5)
				(thermal_bridge_width 0.5)
				(island_removal_mode 0)
			)
			(polygon
				(pts
					(xy 84.455 -98.425) (xy 84.6074 -98.425) (xy 84.6074 -99.0346) (xy 84.455 -99.0346)
				)
			)
		)
	)
	(footprint ""
		(layer "F.Cu")
		(at 110.6424 -73.0504 180)
		(property "Reference" "U22"
			(at 0.4064 2.47523 0)
			(unlocked yes)
			(layer "F.SilkS")
			(effects
				(font
					(size 0.7874 0.5842)
					(thickness 0.1524)
				)
			)
		)
		(property "Value" ""
			(at 0 0 180)
			(layer "F.Fab")
			(effects
				(font
					(size 1.27 1.27)
				)
			)
		)
		(property "Device Type" "NCP45560IMNTWG_H_DFN12-G222-10A"
			(at 0.074168 3.118866 180)
			(unlocked yes)
			(layer "F.Fab")
			(hide yes)
			(effects
				(font
					(size 0.7874 0.5842)
					(thickness 0.1524)
				)
			)
		)
		(property "User Part Number" "PARTNUM*"
			(at 0.074168 4.312666 180)
			(unlocked yes)
			(layer "Cmts.User")
			(hide yes)
			(effects
				(font
					(size 0.7874 0.5842)
					(thickness 0.1524)
				)
			)
		)
		(duplicate_pad_numbers_are_jumpers no)
		(fp_line
			(start 2.29235 1.754124)
			(end -2.29235 1.754124)
			(stroke
				(width 0.1)
				(type default)
			)
			(layer "F.SilkS")
		)
		(fp_line
			(start 2.29235 -1.783334)
			(end 2.29235 1.754124)
			(stroke
				(width 0.1)
				(type default)
			)
			(layer "F.SilkS")
		)
		(fp_line
			(start -2.29235 1.754124)
			(end -2.29235 -1.783334)
			(stroke
				(width 0.1)
				(type default)
			)
			(layer "F.SilkS")
		)
		(fp_line
			(start -2.29235 -1.783334)
			(end 2.29235 -1.783334)
			(stroke
				(width 0.1)
				(type default)
			)
			(layer "F.SilkS")
		)
		(fp_poly
			(pts
				(arc
					(start -3.7846 -1.930146)
					(mid -2.769108 -1.930146)
					(end -3.7846 -1.930146)
				)
			)
			(stroke
				(width 0)
				(type default)
			)
			(fill yes)
			(layer "F.SilkS")
		)
		(fp_rect
			(start 0.1016 -0.1016)
			(end 0.9017 -1.2192)
			(stroke
				(width 0)
				(type default)
			)
			(fill yes)
			(layer "F.Paste")
		)
		(fp_rect
			(start -0.9017 1.2192)
			(end -0.1016 0.1016)
			(stroke
				(width 0)
				(type default)
			)
			(fill yes)
			(layer "F.Paste")
		)
		(fp_poly
			(pts
				(xy 0.9017 0.1016)
				(arc
					(start 0.9017 0.9652)
					(mid 0.468095 0.785595)
					(end 0.6477 1.2192)
				)
				(xy 0.1016 1.2192) (xy 0.1016 0.1016)
			)
			(stroke
				(width 0)
				(type default)
			)
			(fill yes)
			(layer "F.Paste")
		)
		(fp_poly
			(pts
				(xy -0.9017 -0.1016)
				(arc
					(start -0.9017 -0.9652)
					(mid -0.468095 -0.785595)
					(end -0.6477 -1.2192)
				)
				(xy -0.1016 -1.2192) (xy -0.1016 -0.1016)
			)
			(stroke
				(width 0)
				(type default)
			)
			(fill yes)
			(layer "F.Paste")
		)
		(fp_poly
			(pts
				(xy -2.54635 2.008124) (xy 2.54635 2.008124) (xy 2.54635 -2.037334) (xy -2.54635 -2.037334)
			)
			(stroke
				(width 0)
				(type default)
			)
			(fill no)
			(layer "F.CrtYd")
		)
		(fp_line
			(start 1.500124 1.500124)
			(end 1.500124 -1.500124)
			(stroke
				(width 0.1)
				(type default)
			)
			(layer "F.Fab")
		)
		(fp_line
			(start 1.500124 -1.500124)
			(end -1.500124 -1.500124)
			(stroke
				(width 0.1)
				(type default)
			)
			(layer "F.Fab")
		)
		(fp_line
			(start -1.500124 1.500124)
			(end 1.500124 1.500124)
			(stroke
				(width 0.1)
				(type default)
			)
			(layer "F.Fab")
		)
		(fp_line
			(start -1.500124 -1.500124)
			(end -1.500124 1.500124)
			(stroke
				(width 0.1)
				(type default)
			)
			(layer "F.Fab")
		)
		(fp_poly
			(pts
				(arc
					(start -3.2766 -1.803146)
					(mid -2.261108 -1.803146)
					(end -3.2766 -1.803146)
				)
			)
			(stroke
				(width 0)
				(type default)
			)
			(fill yes)
			(layer "F.Fab")
		)
		(fp_text user "7"
			(at 2.8194 2.02565 0)
			(unlocked yes)
			(layer "F.SilkS")
			(effects
				(font
					(size 0.635 0.4064)
					(thickness 0.1524)
				)
			)
		)
		(fp_text user "12"
			(at 2.3114 -2.34315 0)
			(unlocked yes)
			(layer "F.SilkS")
			(effects
				(font
					(size 0.635 0.4064)
					(thickness 0.1524)
				)
			)
		)
		(fp_text user "6"
			(at -3.1496 1.21285 0)
			(unlocked yes)
			(layer "F.SilkS")
			(effects
				(font
					(size 0.635 0.4064)
					(thickness 0.1524)
				)
			)
		)
		(fp_text user "12"
			(at 2.6924 -1.96977 0)
			(unlocked yes)
			(layer "F.Fab")
			(effects
				(font
					(size 0.7874 0.5842)
					(thickness 0.1524)
				)
			)
		)
		(fp_text user "7"
			(at 2.5654 1.58623 0)
			(unlocked yes)
			(layer "F.Fab")
			(effects
				(font
					(size 0.7874 0.5842)
					(thickness 0.1524)
				)
			)
		)
		(fp_text user "6"
			(at -2.758948 1.418336 0)
			(unlocked yes)
			(layer "F.Fab")
			(effects
				(font
					(size 0.7874 0.5842)
					(thickness 0.1524)
				)
			)
		)
		(pad "1" smd rect
			(at -1.61925 -1.313434 180)
			(size 0.8382 0.4318)
			(layers "F.Cu" "F.Mask" "F.Paste")
			(net "XP3R3V")
		)
		(pad "2" smd rect
			(at -1.61925 -0.750062 180)
			(size 0.8382 0.3048)
			(layers "F.Cu" "F.Mask" "F.Paste")
			(net "XP3R3V_FPGA_EN_R")
		)
		(pad "3" smd rect
			(at -1.61925 -0.249936 180)
			(size 0.8382 0.3048)
			(layers "F.Cu" "F.Mask" "F.Paste")
			(net "XP3R3V")
		)
		(pad "4" smd rect
			(at -1.61925 0.249936 180)
			(size 0.8382 0.3048)
			(layers "F.Cu" "F.Mask" "F.Paste")
			(net "SG")
		)
		(pad "5" smd rect
			(at -1.61925 0.750062 180)
			(size 0.8382 0.3048)
			(layers "F.Cu" "F.Mask" "F.Paste")
			(net "XP3R3V_FPGA_SR")
		)
		(pad "6" smd rect
			(at -1.61925 1.249934 180)
			(size 0.8382 0.3048)
			(layers "F.Cu" "F.Mask" "F.Paste")
			(net "UNNAMED_515_NCP45560IMNTWGHDFN1")
		)
		(pad "7" smd rect
			(at 1.61925 1.249934 180)
			(size 0.8382 0.3048)
			(layers "F.Cu" "F.Mask" "F.Paste")
			(net "XP3R3V_FPGA")
		)
		(pad "8" smd rect
			(at 1.61925 0.750062 180)
			(size 0.8382 0.3048)
			(layers "F.Cu" "F.Mask" "F.Paste")
			(net "XP3R3V_FPGA")
		)
		(pad "9" smd rect
			(at 1.61925 0.249936 180)
			(size 0.8382 0.3048)
			(layers "F.Cu" "F.Mask" "F.Paste")
			(net "XP3R3V_FPGA")
		)
		(pad "10" smd rect
			(at 1.61925 -0.249936 180)
			(size 0.8382 0.3048)
			(layers "F.Cu" "F.Mask" "F.Paste")
			(net "XP3R3V_FPGA")
		)
		(pad "11" smd rect
			(at 1.61925 -0.750062 180)
			(size 0.8382 0.3048)
			(layers "F.Cu" "F.Mask" "F.Paste")
			(net "XP3R3V_FPGA")
		)
		(pad "12" smd rect
			(at 1.61925 -1.249934 180)
			(size 0.8382 0.3048)
			(layers "F.Cu" "F.Mask" "F.Paste")
			(net "XP3R3V_FPGA")
		)
		(pad "13" smd rect
			(at 0 0 180)
			(size 1.8034 2.4384)
			(layers "F.Cu" "F.Mask" "F.Paste")
			(net "XP3R3V")
		)
	)
)
